# T6G (Grand Teton) — schematic netlist excerpt (pin names and nets, part order shuffled) for the footprints in the layout excerpt that follows; sources: Cadence DE-HDL packaged netlist, KiCad conversion of 04192023_DAF0TMB3IC0_F0TG_MB_C_brd_V02_OCP.brd

C8360  Q_CAP  1000PF 50V 5% EMPTY  pkg 0402  page 217 : A = PWRGD_PVDDCR_CPU1_P1_R ; B = GND
PC2161  Q_CAP  0.068UF 16V 10% X7R  pkg 0402  page 135 : A = P3V3_OCP_DVDT_1 ; B = GND

(kicad_pcb
	(version 20260206)
	(generator "pcbnew")
	(generator_version "10.0")
	(general
		(thickness 1.6)
		(legacy_teardrops no)
	)
	(paper "A4")
	(title_block
		(title "04192023_DAF0TMB3IC0_F0TG_MB_C_brd_V02_OCP.brd")
		(comment 1 "Grand Teton / footprints 2688-2689 of 8354")
	)
	(layers
		(0 "F.Cu" signal "TOP")
		(4 "In1.Cu" signal "GND")
		(6 "In2.Cu" signal "IN1")
		(8 "In3.Cu" signal "GND1")
		(10 "In4.Cu" signal "IN2")
		(12 "In5.Cu" signal "GND2")
		(14 "In6.Cu" signal "IN3")
		(16 "In7.Cu" signal "GND3")
		(18 "In8.Cu" signal "VCC")
		(20 "In9.Cu" signal "VCC1")
		(22 "In10.Cu" signal "GND4")
		(24 "In11.Cu" signal "IN4")
		(26 "In12.Cu" signal "GND5")
		(28 "In13.Cu" signal "IN5")
		(30 "In14.Cu" signal "GND6")
		(32 "In15.Cu" signal "IN6")
		(34 "In16.Cu" signal "GND7")
		(2 "B.Cu" signal "BOTTOM")
		(9 "F.Adhes" user "F.Adhesive")
		(11 "B.Adhes" user "B.Adhesive")
		(13 "F.Paste" user "Package Geometry/Pastemask Top")
		(15 "B.Paste" user "Package Geometry/Pastemask Bottom")
		(5 "F.SilkS" user "Ref Des/Silkscreen Top")
		(7 "B.SilkS" user "Ref Des/Silkscreen Bottom")
		(1 "F.Mask" user "Board Geometry/Soldermask Top")
		(3 "B.Mask" user "Board Geometry/Soldermask Bottom")
		(17 "Dwgs.User" user "User.Drawings")
		(19 "Cmts.User" user "User.Comments")
		(21 "Eco1.User" user "User.Eco1")
		(23 "Eco2.User" user "User.Eco2")
		(25 "Edge.Cuts" user "Board Geometry/Outline")
		(27 "Margin" user)
		(31 "F.CrtYd" user "Package Geometry/Place Bound Top")
		(29 "B.CrtYd" user "Package Geometry/Place Bound Bottom")
		(35 "F.Fab" user "Ref Des/Assembly Top")
		(33 "B.Fab" user "Ref Des/Assembly Bottom")
	)
	(footprint ""
		(layer "F.Cu")
		(at 24.765 -365.76 180)
		(property "Reference" "C8360"
			(at 0 0 180)
			(layer "F.SilkS")
			(hide yes)
			(effects
				(font
					(size 1.27 1.27)
				)
			)
		)
		(property "Value" ""
			(at 0 0 180)
			(layer "F.Fab")
			(effects
				(font
					(size 1.27 1.27)
				)
			)
		)
		(duplicate_pad_numbers_are_jumpers no)
		(fp_line
			(start 0.7874 0.4064)
			(end -0.7874 0.4064)
			(stroke
				(width 0.1524)
				(type default)
			)
			(layer "F.SilkS")
		)
		(fp_line
			(start 0.7874 -0.4064)
			(end 0.7874 0.4064)
			(stroke
				(width 0.1524)
				(type default)
			)
			(layer "F.SilkS")
		)
		(fp_line
			(start -0.7874 0.4064)
			(end -0.7874 -0.4064)
			(stroke
				(width 0.1524)
				(type default)
			)
			(layer "F.SilkS")
		)
		(fp_line
			(start -0.7874 -0.4064)
			(end 0.7874 -0.4064)
			(stroke
				(width 0.1524)
				(type default)
			)
			(layer "F.SilkS")
		)
		(fp_line
			(start 0.67945 0.3048)
			(end 0.120396 0.3048)
			(stroke
				(width 0.1)
				(type default)
			)
			(layer "F.Fab")
		)
		(fp_line
			(start 0.67945 -0.3048)
			(end 0.67945 0.3048)
			(stroke
				(width 0.1)
				(type default)
			)
			(layer "F.Fab")
		)
		(fp_line
			(start 0.12065 -0.2794)
			(end 0.12065 -0.3048)
			(stroke
				(width 0.1)
				(type default)
			)
			(layer "F.Fab")
		)
		(fp_line
			(start 0.12065 -0.3048)
			(end 0.67945 -0.3048)
			(stroke
				(width 0.1)
				(type default)
			)
			(layer "F.Fab")
		)
		(fp_line
			(start 0.120396 0.3048)
			(end 0.120396 0.2794)
			(stroke
				(width 0.1)
				(type default)
			)
			(layer "F.Fab")
		)
		(fp_line
			(start 0.120396 0.2794)
			(end -0.12065 0.2794)
			(stroke
				(width 0.1)
				(type default)
			)
			(layer "F.Fab")
		)
		(fp_line
			(start -0.12065 0.3048)
			(end -0.67945 0.3048)
			(stroke
				(width 0.1)
				(type default)
			)
			(layer "F.Fab")
		)
		(fp_line
			(start -0.12065 0.2794)
			(end -0.12065 0.3048)
			(stroke
				(width 0.1)
				(type default)
			)
			(layer "F.Fab")
		)
		(fp_line
			(start -0.12065 -0.2794)
			(end 0.12065 -0.2794)
			(stroke
				(width 0.1)
				(type default)
			)
			(layer "F.Fab")
		)
		(fp_line
			(start -0.12065 -0.305054)
			(end -0.12065 -0.2794)
			(stroke
				(width 0.1)
				(type default)
			)
			(layer "F.Fab")
		)
		(fp_line
			(start -0.67945 0.3048)
			(end -0.67945 -0.305054)
			(stroke
				(width 0.1)
				(type default)
			)
			(layer "F.Fab")
		)
		(fp_line
			(start -0.67945 -0.305054)
			(end -0.12065 -0.305054)
			(stroke
				(width 0.1)
				(type default)
			)
			(layer "F.Fab")
		)
		(pad "1" smd circle
			(at -0.40005 0 180)
			(size 0 0)
			(layers "F.Cu" "F.Mask" "F.Paste")
			(net "PWRGD_PVDDCR_CPU1_P1_R")
		)
		(pad "2" smd circle
			(at 0.40005 0 180)
			(size 0 0)
			(layers "F.Cu" "F.Mask" "F.Paste")
			(net "GND")
		)
	)
	(footprint ""
		(layer "F.Cu")
		(at 418.21354 -109.231176 90)
		(property "Reference" "PC2161"
			(at 0 0 90)
			(layer "F.SilkS")
			(hide yes)
			(effects
				(font
					(size 1.27 1.27)
				)
			)
		)
		(property "Value" ""
			(at 0 0 90)
			(layer "F.Fab")
			(effects
				(font
					(size 1.27 1.27)
				)
			)
		)
		(duplicate_pad_numbers_are_jumpers no)
		(fp_line
			(start 0.7874 -0.4064)
			(end 0.7874 0.4064)
			(stroke
				(width 0.1524)
				(type default)
			)
			(layer "F.SilkS")
		)
		(fp_line
			(start -0.7874 -0.4064)
			(end 0.7874 -0.4064)
			(stroke
				(width 0.1524)
				(type default)
			)
			(layer "F.SilkS")
		)
		(fp_line
			(start 0.7874 0.4064)
			(end -0.7874 0.4064)
			(stroke
				(width 0.1524)
				(type default)
			)
			(layer "F.SilkS")
		)
		(fp_line
			(start -0.7874 0.4064)
			(end -0.7874 -0.4064)
			(stroke
				(width 0.1524)
				(type default)
			)
			(layer "F.SilkS")
		)
		(fp_line
			(start -0.12065 -0.305054)
			(end -0.12065 -0.2794)
			(stroke
				(width 0.1)
				(type default)
			)
			(layer "F.Fab")
		)
		(fp_line
			(start -0.67945 -0.305054)
			(end -0.12065 -0.305054)
			(stroke
				(width 0.1)
				(type default)
			)
			(layer "F.Fab")
		)
		(fp_line
			(start 0.67945 -0.3048)
			(end 0.67945 0.3048)
			(stroke
				(width 0.1)
				(type default)
			)
			(layer "F.Fab")
		)
		(fp_line
			(start 0.12065 -0.3048)
			(end 0.67945 -0.3048)
			(stroke
				(width 0.1)
				(type default)
			)
			(layer "F.Fab")
		)
		(fp_line
			(start 0.12065 -0.2794)
			(end 0.12065 -0.3048)
			(stroke
				(width 0.1)
				(type default)
			)
			(layer "F.Fab")
		)
		(fp_line
			(start -0.12065 -0.2794)
			(end 0.12065 -0.2794)
			(stroke
				(width 0.1)
				(type default)
			)
			(layer "F.Fab")
		)
		(fp_line
			(start 0.120396 0.2794)
			(end -0.12065 0.2794)
			(stroke
				(width 0.1)
				(type default)
			)
			(layer "F.Fab")
		)
		(fp_line
			(start -0.12065 0.2794)
			(end -0.12065 0.3048)
			(stroke
				(width 0.1)
				(type default)
			)
			(layer "F.Fab")
		)
		(fp_line
			(start 0.67945 0.3048)
			(end 0.120396 0.3048)
			(stroke
				(width 0.1)
				(type default)
			)
			(layer "F.Fab")
		)
		(fp_line
			(start 0.120396 0.3048)
			(end 0.120396 0.2794)
			(stroke
				(width 0.1)
				(type default)
			)
			(layer "F.Fab")
		)
		(fp_line
			(start -0.12065 0.3048)
			(end -0.67945 0.3048)
			(stroke
				(width 0.1)
				(type default)
			)
			(layer "F.Fab")
		)
		(fp_line
			(start -0.67945 0.3048)
			(end -0.67945 -0.305054)
			(stroke
				(width 0.1)
				(type default)
			)
			(layer "F.Fab")
		)
		(pad "1" smd circle
			(at -0.40005 0 90)
			(size 0 0)
			(layers "F.Cu" "F.Mask" "F.Paste")
			(net "P3V3_OCP_DVDT_1")
		)
		(pad "2" smd circle
			(at 0.40005 0 90)
			(size 0 0)
			(layers "F.Cu" "F.Mask" "F.Paste")
			(net "GND")
		)
	)
)
